# T6G (Grand Teton) — schematic netlist excerpt (pin names and nets, part order shuffled) for the footprints in the layout excerpt that follows; sources: Cadence DE-HDL packaged netlist, KiCad conversion of 04192023_DAF0TMB3IC0_F0TG_MB_C_brd_V02_OCP.brd

PC2163  Q_CAP  10UF 16V 10% X6S  pkg C0805  page 135 : A = P3V3_OCP_SFF_R ; B = GND
R3576  Q_RES  0 5% CHIP  pkg 0402LF  page 237 : A = SMB_INA230_5_3V3AUX_SCL_R ; B = SMB_INA230_5_3V3AUX_SCL_R1
R3337  Q_RES  0 5% CHIP  pkg 0402LF  page 233 : A = CLK_100M_GPU_FPGA_DP_R ; B = CLK_100M_GPU_FPGA_DP

(kicad_pcb
	(version 20260206)
	(generator "pcbnew")
	(generator_version "10.0")
	(general
		(thickness 1.6)
		(legacy_teardrops no)
	)
	(paper "A4")
	(title_block
		(title "04192023_DAF0TMB3IC0_F0TG_MB_C_brd_V02_OCP.brd")
		(comment 1 "Grand Teton / footprints 1928-1930 of 8354")
	)
	(layers
		(0 "F.Cu" signal "TOP")
		(4 "In1.Cu" signal "GND")
		(6 "In2.Cu" signal "IN1")
		(8 "In3.Cu" signal "GND1")
		(10 "In4.Cu" signal "IN2")
		(12 "In5.Cu" signal "GND2")
		(14 "In6.Cu" signal "IN3")
		(16 "In7.Cu" signal "GND3")
		(18 "In8.Cu" signal "VCC")
		(20 "In9.Cu" signal "VCC1")
		(22 "In10.Cu" signal "GND4")
		(24 "In11.Cu" signal "IN4")
		(26 "In12.Cu" signal "GND5")
		(28 "In13.Cu" signal "IN5")
		(30 "In14.Cu" signal "GND6")
		(32 "In15.Cu" signal "IN6")
		(34 "In16.Cu" signal "GND7")
		(2 "B.Cu" signal "BOTTOM")
		(9 "F.Adhes" user "F.Adhesive")
		(11 "B.Adhes" user "B.Adhesive")
		(13 "F.Paste" user "Package Geometry/Pastemask Top")
		(15 "B.Paste" user "Package Geometry/Pastemask Bottom")
		(5 "F.SilkS" user "Ref Des/Silkscreen Top")
		(7 "B.SilkS" user "Ref Des/Silkscreen Bottom")
		(1 "F.Mask" user "Board Geometry/Soldermask Top")
		(3 "B.Mask" user "Board Geometry/Soldermask Bottom")
		(17 "Dwgs.User" user "User.Drawings")
		(19 "Cmts.User" user "User.Comments")
		(21 "Eco1.User" user "User.Eco1")
		(23 "Eco2.User" user "User.Eco2")
		(25 "Edge.Cuts" user "Board Geometry/Outline")
		(27 "Margin" user)
		(31 "F.CrtYd" user "Package Geometry/Place Bound Top")
		(29 "B.CrtYd" user "Package Geometry/Place Bound Bottom")
		(35 "F.Fab" user "Ref Des/Assembly Top")
		(33 "B.Fab" user "Ref Des/Assembly Bottom")
	)
	(footprint ""
		(layer "F.Cu")
		(at 213.54288 -34.508948 180)
		(property "Reference" "R3576"
			(at 0 0 180)
			(layer "F.SilkS")
			(hide yes)
			(effects
				(font
					(size 1.27 1.27)
				)
			)
		)
		(property "Value" ""
			(at 0 0 180)
			(layer "F.Fab")
			(effects
				(font
					(size 1.27 1.27)
				)
			)
		)
		(duplicate_pad_numbers_are_jumpers no)
		(fp_line
			(start 0.7874 0.4064)
			(end -0.7874 0.4064)
			(stroke
				(width 0.1524)
				(type default)
			)
			(layer "F.SilkS")
		)
		(fp_line
			(start 0.7874 -0.4064)
			(end 0.7874 0.4064)
			(stroke
				(width 0.1524)
				(type default)
			)
			(layer "F.SilkS")
		)
		(fp_line
			(start -0.7874 0.4064)
			(end -0.7874 -0.4064)
			(stroke
				(width 0.1524)
				(type default)
			)
			(layer "F.SilkS")
		)
		(fp_line
			(start -0.7874 -0.4064)
			(end 0.7874 -0.4064)
			(stroke
				(width 0.1524)
				(type default)
			)
			(layer "F.SilkS")
		)
		(fp_line
			(start 0.67945 0.3048)
			(end 0.120396 0.3048)
			(stroke
				(width 0.1)
				(type default)
			)
			(layer "F.Fab")
		)
		(fp_line
			(start 0.67945 -0.3048)
			(end 0.67945 0.3048)
			(stroke
				(width 0.1)
				(type default)
			)
			(layer "F.Fab")
		)
		(fp_line
			(start 0.12065 -0.2794)
			(end 0.12065 -0.3048)
			(stroke
				(width 0.1)
				(type default)
			)
			(layer "F.Fab")
		)
		(fp_line
			(start 0.12065 -0.3048)
			(end 0.67945 -0.3048)
			(stroke
				(width 0.1)
				(type default)
			)
			(layer "F.Fab")
		)
		(fp_line
			(start 0.120396 0.3048)
			(end 0.120396 0.2794)
			(stroke
				(width 0.1)
				(type default)
			)
			(layer "F.Fab")
		)
		(fp_line
			(start 0.120396 0.2794)
			(end -0.12065 0.2794)
			(stroke
				(width 0.1)
				(type default)
			)
			(layer "F.Fab")
		)
		(fp_line
			(start -0.12065 0.3048)
			(end -0.67945 0.3048)
			(stroke
				(width 0.1)
				(type default)
			)
			(layer "F.Fab")
		)
		(fp_line
			(start -0.12065 0.2794)
			(end -0.12065 0.3048)
			(stroke
				(width 0.1)
				(type default)
			)
			(layer "F.Fab")
		)
		(fp_line
			(start -0.12065 -0.2794)
			(end 0.12065 -0.2794)
			(stroke
				(width 0.1)
				(type default)
			)
			(layer "F.Fab")
		)
		(fp_line
			(start -0.12065 -0.305054)
			(end -0.12065 -0.2794)
			(stroke
				(width 0.1)
				(type default)
			)
			(layer "F.Fab")
		)
		(fp_line
			(start -0.67945 0.3048)
			(end -0.67945 -0.305054)
			(stroke
				(width 0.1)
				(type default)
			)
			(layer "F.Fab")
		)
		(fp_line
			(start -0.67945 -0.305054)
			(end -0.12065 -0.305054)
			(stroke
				(width 0.1)
				(type default)
			)
			(layer "F.Fab")
		)
		(pad "1" smd circle
			(at -0.40005 0 180)
			(size 0 0)
			(layers "F.Cu" "F.Mask" "F.Paste")
			(net "SMB_INA230_5_3V3AUX_SCL_R")
		)
		(pad "2" smd circle
			(at 0.40005 0 180)
			(size 0 0)
			(layers "F.Cu" "F.Mask" "F.Paste")
			(net "SMB_INA230_5_3V3AUX_SCL_R1")
		)
	)
	(footprint ""
		(layer "F.Cu")
		(at 18.702782 -136.985502)
		(property "Reference" "R3337"
			(at 0 0 0)
			(layer "F.SilkS")
			(hide yes)
			(effects
				(font
					(size 1.27 1.27)
				)
			)
		)
		(property "Value" ""
			(at 0 0 0)
			(layer "F.Fab")
			(effects
				(font
					(size 1.27 1.27)
				)
			)
		)
		(duplicate_pad_numbers_are_jumpers no)
		(fp_line
			(start -0.7874 -0.4064)
			(end 0.7874 -0.4064)
			(stroke
				(width 0.1524)
				(type default)
			)
			(layer "F.SilkS")
		)
		(fp_line
			(start -0.7874 0.4064)
			(end -0.7874 -0.4064)
			(stroke
				(width 0.1524)
				(type default)
			)
			(layer "F.SilkS")
		)
		(fp_line
			(start 0.7874 -0.4064)
			(end 0.7874 0.4064)
			(stroke
				(width 0.1524)
				(type default)
			)
			(layer "F.SilkS")
		)
		(fp_line
			(start 0.7874 0.4064)
			(end -0.7874 0.4064)
			(stroke
				(width 0.1524)
				(type default)
			)
			(layer "F.SilkS")
		)
		(fp_line
			(start -0.67945 -0.305054)
			(end -0.12065 -0.305054)
			(stroke
				(width 0.1)
				(type default)
			)
			(layer "F.Fab")
		)
		(fp_line
			(start -0.67945 0.3048)
			(end -0.67945 -0.305054)
			(stroke
				(width 0.1)
				(type default)
			)
			(layer "F.Fab")
		)
		(fp_line
			(start -0.12065 -0.305054)
			(end -0.12065 -0.2794)
			(stroke
				(width 0.1)
				(type default)
			)
			(layer "F.Fab")
		)
		(fp_line
			(start -0.12065 -0.2794)
			(end 0.12065 -0.2794)
			(stroke
				(width 0.1)
				(type default)
			)
			(layer "F.Fab")
		)
		(fp_line
			(start -0.12065 0.2794)
			(end -0.12065 0.3048)
			(stroke
				(width 0.1)
				(type default)
			)
			(layer "F.Fab")
		)
		(fp_line
			(start -0.12065 0.3048)
			(end -0.67945 0.3048)
			(stroke
				(width 0.1)
				(type default)
			)
			(layer "F.Fab")
		)
		(fp_line
			(start 0.120396 0.2794)
			(end -0.12065 0.2794)
			(stroke
				(width 0.1)
				(type default)
			)
			(layer "F.Fab")
		)
		(fp_line
			(start 0.120396 0.3048)
			(end 0.120396 0.2794)
			(stroke
				(width 0.1)
				(type default)
			)
			(layer "F.Fab")
		)
		(fp_line
			(start 0.12065 -0.3048)
			(end 0.67945 -0.3048)
			(stroke
				(width 0.1)
				(type default)
			)
			(layer "F.Fab")
		)
		(fp_line
			(start 0.12065 -0.2794)
			(end 0.12065 -0.3048)
			(stroke
				(width 0.1)
				(type default)
			)
			(layer "F.Fab")
		)
		(fp_line
			(start 0.67945 -0.3048)
			(end 0.67945 0.3048)
			(stroke
				(width 0.1)
				(type default)
			)
			(layer "F.Fab")
		)
		(fp_line
			(start 0.67945 0.3048)
			(end 0.120396 0.3048)
			(stroke
				(width 0.1)
				(type default)
			)
			(layer "F.Fab")
		)
		(pad "1" smd circle
			(at -0.40005 0)
			(size 0 0)
			(layers "F.Cu" "F.Mask" "F.Paste")
			(net "CLK_100M_GPU_FPGA_DP_R")
		)
		(pad "2" smd circle
			(at 0.40005 0)
			(size 0 0)
			(layers "F.Cu" "F.Mask" "F.Paste")
			(net "CLK_100M_GPU_FPGA_DP")
		)
	)
	(footprint ""
		(layer "F.Cu")
		(at 423.56278 -106.129328 90)
		(property "Reference" "PC2163"
			(at 0 0 90)
			(layer "F.SilkS")
			(hide yes)
			(effects
				(font
					(size 1.27 1.27)
				)
			)
		)
		(property "Value" ""
			(at 0 0 90)
			(layer "F.Fab")
			(effects
				(font
					(size 1.27 1.27)
				)
			)
		)
		(duplicate_pad_numbers_are_jumpers no)
		(fp_line
			(start 1.524 -0.762)
			(end 1.524 0.762)
			(stroke
				(width 0.1524)
				(type default)
			)
			(layer "F.SilkS")
		)
		(fp_line
			(start -1.524 -0.762)
			(end 1.524 -0.762)
			(stroke
				(width 0.1524)
				(type default)
			)
			(layer "F.SilkS")
		)
		(fp_line
			(start 1.524 0.762)
			(end -1.524 0.762)
			(stroke
				(width 0.1524)
				(type default)
			)
			(layer "F.SilkS")
		)
		(fp_line
			(start -1.524 0.762)
			(end -1.524 -0.762)
			(stroke
				(width 0.1524)
				(type default)
			)
			(layer "F.SilkS")
		)
		(fp_line
			(start 1.1049 -0.724916)
			(end -1.1049 -0.724916)
			(stroke
				(width 0.1)
				(type default)
			)
			(layer "F.Fab")
		)
		(fp_line
			(start -1.1049 -0.724916)
			(end -1.1049 0.724916)
			(stroke
				(width 0.1)
				(type default)
			)
			(layer "F.Fab")
		)
		(fp_line
			(start 1.1049 0.724916)
			(end 1.1049 -0.724916)
			(stroke
				(width 0.1)
				(type default)
			)
			(layer "F.Fab")
		)
		(fp_line
			(start -1.1049 0.724916)
			(end 1.1049 0.724916)
			(stroke
				(width 0.1)
				(type default)
			)
			(layer "F.Fab")
		)
		(pad "1" smd rect
			(at -0.889 0 270)
			(size 1.016 1.27)
			(layers "F.Cu" "F.Mask" "F.Paste")
			(net "P3V3_OCP_SFF_R")
		)
		(pad "2" smd rect
			(at 0.889 0 270)
			(size 1.016 1.27)
			(layers "F.Cu" "F.Mask" "F.Paste")
			(net "GND")
		)
	)
)
